(kicad_pcb
	(version 20260206)
	(generator "pcbnew")
	(generator_version "10.0")
	(general
		(thickness 1.6)
		(legacy_teardrops no)
	)
	(paper "A4")
	(title_block
		(title "12092022_DA0F0TMDCD0_F0T_Management_Board_D_brd_V3_OCP.brd")
		(comment 1 "Grand Teton / footprints 702-708 of 1440")
	)
	(layers
		(0 "F.Cu" signal "TOP")
		(4 "In1.Cu" signal "GND")
		(6 "In2.Cu" signal "IN1")
		(8 "In3.Cu" signal "GND1")
		(10 "In4.Cu" signal "IN2")
		(12 "In5.Cu" signal "VCC")
		(14 "In6.Cu" signal "VCC1")
		(16 "In7.Cu" signal "IN3")
		(18 "In8.Cu" signal "GND2")
		(20 "In9.Cu" signal "IN4")
		(22 "In10.Cu" signal "GND3")
		(2 "B.Cu" signal "BOTTOM")
		(9 "F.Adhes" user "F.Adhesive")
		(11 "B.Adhes" user "B.Adhesive")
		(13 "F.Paste" user "Package Geometry/Pastemask Top")
		(15 "B.Paste" user "Package Geometry/Pastemask Bottom")
		(5 "F.SilkS" user "Ref Des/Silkscreen Top")
		(7 "B.SilkS" user "Ref Des/Silkscreen Bottom")
		(1 "F.Mask" user "Board Geometry/Soldermask Top")
		(3 "B.Mask" user "Board Geometry/Soldermask Bottom")
		(17 "Dwgs.User" user "User.Drawings")
		(19 "Cmts.User" user "User.Comments")
		(21 "Eco1.User" user "User.Eco1")
		(23 "Eco2.User" user "User.Eco2")
		(25 "Edge.Cuts" user "Board Geometry/Outline")
		(27 "Margin" user)
		(31 "F.CrtYd" user "Package Geometry/Place Bound Top")
		(29 "B.CrtYd" user "Package Geometry/Place Bound Bottom")
		(35 "F.Fab" user "Ref Des/Assembly Top")
		(33 "B.Fab" user "Ref Des/Assembly Bottom")
	)
	(footprint ""
		(layer "F.Cu")
		(at 18.4912 -46.3042 -90)
		(property "Reference" "R563"
			(at 0 0 270)
			(layer "F.SilkS")
			(hide yes)
			(effects
				(font
					(size 1.27 1.27)
				)
			)
		)
		(property "Value" ""
			(at 0 0 270)
			(layer "F.Fab")
			(effects
				(font
					(size 1.27 1.27)
				)
			)
		)
		(duplicate_pad_numbers_are_jumpers no)
		(fp_line
			(start -0.7874 0.4064)
			(end -0.7874 -0.4064)
			(stroke
				(width 0.1524)
				(type default)
			)
			(layer "F.SilkS")
		)
		(fp_line
			(start 0.7874 0.4064)
			(end -0.7874 0.4064)
			(stroke
				(width 0.1524)
				(type default)
			)
			(layer "F.SilkS")
		)
		(fp_line
			(start -0.7874 -0.4064)
			(end 0.7874 -0.4064)
			(stroke
				(width 0.1524)
				(type default)
			)
			(layer "F.SilkS")
		)
		(fp_line
			(start 0.7874 -0.4064)
			(end 0.7874 0.4064)
			(stroke
				(width 0.1524)
				(type default)
			)
			(layer "F.SilkS")
		)
		(fp_line
			(start -0.67945 0.3048)
			(end -0.67945 -0.305054)
			(stroke
				(width 0.1)
				(type default)
			)
			(layer "F.Fab")
		)
		(fp_line
			(start -0.12065 0.3048)
			(end -0.67945 0.3048)
			(stroke
				(width 0.1)
				(type default)
			)
			(layer "F.Fab")
		)
		(fp_line
			(start 0.120396 0.3048)
			(end 0.120396 0.2794)
			(stroke
				(width 0.1)
				(type default)
			)
			(layer "F.Fab")
		)
		(fp_line
			(start 0.67945 0.3048)
			(end 0.120396 0.3048)
			(stroke
				(width 0.1)
				(type default)
			)
			(layer "F.Fab")
		)
		(fp_line
			(start -0.12065 0.2794)
			(end -0.12065 0.3048)
			(stroke
				(width 0.1)
				(type default)
			)
			(layer "F.Fab")
		)
		(fp_line
			(start 0.120396 0.2794)
			(end -0.12065 0.2794)
			(stroke
				(width 0.1)
				(type default)
			)
			(layer "F.Fab")
		)
		(fp_line
			(start -0.12065 -0.2794)
			(end 0.12065 -0.2794)
			(stroke
				(width 0.1)
				(type default)
			)
			(layer "F.Fab")
		)
		(fp_line
			(start 0.12065 -0.2794)
			(end 0.12065 -0.3048)
			(stroke
				(width 0.1)
				(type default)
			)
			(layer "F.Fab")
		)
		(fp_line
			(start 0.12065 -0.3048)
			(end 0.67945 -0.3048)
			(stroke
				(width 0.1)
				(type default)
			)
			(layer "F.Fab")
		)
		(fp_line
			(start 0.67945 -0.3048)
			(end 0.67945 0.3048)
			(stroke
				(width 0.1)
				(type default)
			)
			(layer "F.Fab")
		)
		(fp_line
			(start -0.67945 -0.305054)
			(end -0.12065 -0.305054)
			(stroke
				(width 0.1)
				(type default)
			)
			(layer "F.Fab")
		)
		(fp_line
			(start -0.12065 -0.305054)
			(end -0.12065 -0.2794)
			(stroke
				(width 0.1)
				(type default)
			)
			(layer "F.Fab")
		)
		(pad "1" smd circle
			(at -0.40005 0 270)
			(size 0 0)
			(layers "F.Cu" "F.Mask" "F.Paste")
			(net "P3V3_AUX")
		)
		(pad "2" smd circle
			(at 0.40005 0 270)
			(size 0 0)
			(layers "F.Cu" "F.Mask" "F.Paste")
			(net "RST_SPI_FLASH_BUF_N")
		)
	)
	(footprint ""
		(layer "F.Cu")
		(at 31.983172 -83.816952 -90)
		(property "Reference" "R658"
			(at 0 0 270)
			(layer "F.SilkS")
			(hide yes)
			(effects
				(font
					(size 1.27 1.27)
				)
			)
		)
		(property "Value" ""
			(at 0 0 270)
			(layer "F.Fab")
			(effects
				(font
					(size 1.27 1.27)
				)
			)
		)
		(duplicate_pad_numbers_are_jumpers no)
		(fp_line
			(start -0.7874 0.4064)
			(end -0.7874 -0.4064)
			(stroke
				(width 0.1524)
				(type default)
			)
			(layer "F.SilkS")
		)
		(fp_line
			(start 0.7874 0.4064)
			(end -0.7874 0.4064)
			(stroke
				(width 0.1524)
				(type default)
			)
			(layer "F.SilkS")
		)
		(fp_line
			(start -0.7874 -0.4064)
			(end 0.7874 -0.4064)
			(stroke
				(width 0.1524)
				(type default)
			)
			(layer "F.SilkS")
		)
		(fp_line
			(start 0.7874 -0.4064)
			(end 0.7874 0.4064)
			(stroke
				(width 0.1524)
				(type default)
			)
			(layer "F.SilkS")
		)
		(fp_line
			(start -0.67945 0.3048)
			(end -0.67945 -0.305054)
			(stroke
				(width 0.1)
				(type default)
			)
			(layer "F.Fab")
		)
		(fp_line
			(start -0.12065 0.3048)
			(end -0.67945 0.3048)
			(stroke
				(width 0.1)
				(type default)
			)
			(layer "F.Fab")
		)
		(fp_line
			(start 0.120396 0.3048)
			(end 0.120396 0.2794)
			(stroke
				(width 0.1)
				(type default)
			)
			(layer "F.Fab")
		)
		(fp_line
			(start 0.67945 0.3048)
			(end 0.120396 0.3048)
			(stroke
				(width 0.1)
				(type default)
			)
			(layer "F.Fab")
		)
		(fp_line
			(start -0.12065 0.2794)
			(end -0.12065 0.3048)
			(stroke
				(width 0.1)
				(type default)
			)
			(layer "F.Fab")
		)
		(fp_line
			(start 0.120396 0.2794)
			(end -0.12065 0.2794)
			(stroke
				(width 0.1)
				(type default)
			)
			(layer "F.Fab")
		)
		(fp_line
			(start -0.12065 -0.2794)
			(end 0.12065 -0.2794)
			(stroke
				(width 0.1)
				(type default)
			)
			(layer "F.Fab")
		)
		(fp_line
			(start 0.12065 -0.2794)
			(end 0.12065 -0.3048)
			(stroke
				(width 0.1)
				(type default)
			)
			(layer "F.Fab")
		)
		(fp_line
			(start 0.12065 -0.3048)
			(end 0.67945 -0.3048)
			(stroke
				(width 0.1)
				(type default)
			)
			(layer "F.Fab")
		)
		(fp_line
			(start 0.67945 -0.3048)
			(end 0.67945 0.3048)
			(stroke
				(width 0.1)
				(type default)
			)
			(layer "F.Fab")
		)
		(fp_line
			(start -0.67945 -0.305054)
			(end -0.12065 -0.305054)
			(stroke
				(width 0.1)
				(type default)
			)
			(layer "F.Fab")
		)
		(fp_line
			(start -0.12065 -0.305054)
			(end -0.12065 -0.2794)
			(stroke
				(width 0.1)
				(type default)
			)
			(layer "F.Fab")
		)
		(pad "1" smd circle
			(at -0.40005 0 270)
			(size 0 0)
			(layers "F.Cu" "F.Mask" "F.Paste")
			(net "P3V3_AUX")
		)
		(pad "2" smd circle
			(at 0.40005 0 270)
			(size 0 0)
			(layers "F.Cu" "F.Mask" "F.Paste")
			(net "EMMC_DT3_R")
		)
	)
	(footprint ""
		(layer "F.Cu")
		(at 31.75 -28.956)
		(property "Reference" "R87"
			(at 0 0 0)
			(layer "F.SilkS")
			(hide yes)
			(effects
				(font
					(size 1.27 1.27)
				)
			)
		)
		(property "Value" ""
			(at 0 0 0)
			(layer "F.Fab")
			(effects
				(font
					(size 1.27 1.27)
				)
			)
		)
		(duplicate_pad_numbers_are_jumpers no)
		(fp_line
			(start -0.7874 -0.4064)
			(end 0.7874 -0.4064)
			(stroke
				(width 0.1524)
				(type default)
			)
			(layer "F.SilkS")
		)
		(fp_line
			(start -0.7874 0.4064)
			(end -0.7874 -0.4064)
			(stroke
				(width 0.1524)
				(type default)
			)
			(layer "F.SilkS")
		)
		(fp_line
			(start 0.7874 -0.4064)
			(end 0.7874 0.4064)
			(stroke
				(width 0.1524)
				(type default)
			)
			(layer "F.SilkS")
		)
		(fp_line
			(start 0.7874 0.4064)
			(end -0.7874 0.4064)
			(stroke
				(width 0.1524)
				(type default)
			)
			(layer "F.SilkS")
		)
		(fp_line
			(start -0.67945 -0.305054)
			(end -0.12065 -0.305054)
			(stroke
				(width 0.1)
				(type default)
			)
			(layer "F.Fab")
		)
		(fp_line
			(start -0.67945 0.3048)
			(end -0.67945 -0.305054)
			(stroke
				(width 0.1)
				(type default)
			)
			(layer "F.Fab")
		)
		(fp_line
			(start -0.12065 -0.305054)
			(end -0.12065 -0.2794)
			(stroke
				(width 0.1)
				(type default)
			)
			(layer "F.Fab")
		)
		(fp_line
			(start -0.12065 -0.2794)
			(end 0.12065 -0.2794)
			(stroke
				(width 0.1)
				(type default)
			)
			(layer "F.Fab")
		)
		(fp_line
			(start -0.12065 0.2794)
			(end -0.12065 0.3048)
			(stroke
				(width 0.1)
				(type default)
			)
			(layer "F.Fab")
		)
		(fp_line
			(start -0.12065 0.3048)
			(end -0.67945 0.3048)
			(stroke
				(width 0.1)
				(type default)
			)
			(layer "F.Fab")
		)
		(fp_line
			(start 0.120396 0.2794)
			(end -0.12065 0.2794)
			(stroke
				(width 0.1)
				(type default)
			)
			(layer "F.Fab")
		)
		(fp_line
			(start 0.120396 0.3048)
			(end 0.120396 0.2794)
			(stroke
				(width 0.1)
				(type default)
			)
			(layer "F.Fab")
		)
		(fp_line
			(start 0.12065 -0.3048)
			(end 0.67945 -0.3048)
			(stroke
				(width 0.1)
				(type default)
			)
			(layer "F.Fab")
		)
		(fp_line
			(start 0.12065 -0.2794)
			(end 0.12065 -0.3048)
			(stroke
				(width 0.1)
				(type default)
			)
			(layer "F.Fab")
		)
		(fp_line
			(start 0.67945 -0.3048)
			(end 0.67945 0.3048)
			(stroke
				(width 0.1)
				(type default)
			)
			(layer "F.Fab")
		)
		(fp_line
			(start 0.67945 0.3048)
			(end 0.120396 0.3048)
			(stroke
				(width 0.1)
				(type default)
			)
			(layer "F.Fab")
		)
		(pad "1" smd circle
			(at -0.40005 0)
			(size 0 0)
			(layers "F.Cu" "F.Mask" "F.Paste")
			(net "V_DACB_IO")
		)
		(pad "2" smd circle
			(at 0.40005 0)
			(size 0 0)
			(layers "F.Cu" "F.Mask" "F.Paste")
			(net "GND")
		)
	)
	(footprint ""
		(layer "F.Cu")
		(at 83.217258 -36.683442 180)
		(property "Reference" "R829"
			(at 0 0 180)
			(layer "F.SilkS")
			(hide yes)
			(effects
				(font
					(size 1.27 1.27)
				)
			)
		)
		(property "Value" ""
			(at 0 0 180)
			(layer "F.Fab")
			(effects
				(font
					(size 1.27 1.27)
				)
			)
		)
		(duplicate_pad_numbers_are_jumpers no)
		(fp_line
			(start 0.7874 0.4064)
			(end -0.7874 0.4064)
			(stroke
				(width 0.1524)
				(type default)
			)
			(layer "F.SilkS")
		)
		(fp_line
			(start 0.7874 -0.4064)
			(end 0.7874 0.4064)
			(stroke
				(width 0.1524)
				(type default)
			)
			(layer "F.SilkS")
		)
		(fp_line
			(start -0.7874 0.4064)
			(end -0.7874 -0.4064)
			(stroke
				(width 0.1524)
				(type default)
			)
			(layer "F.SilkS")
		)
		(fp_line
			(start -0.7874 -0.4064)
			(end 0.7874 -0.4064)
			(stroke
				(width 0.1524)
				(type default)
			)
			(layer "F.SilkS")
		)
		(fp_line
			(start 0.67945 0.3048)
			(end 0.120396 0.3048)
			(stroke
				(width 0.1)
				(type default)
			)
			(layer "F.Fab")
		)
		(fp_line
			(start 0.67945 -0.3048)
			(end 0.67945 0.3048)
			(stroke
				(width 0.1)
				(type default)
			)
			(layer "F.Fab")
		)
		(fp_line
			(start 0.12065 -0.2794)
			(end 0.12065 -0.3048)
			(stroke
				(width 0.1)
				(type default)
			)
			(layer "F.Fab")
		)
		(fp_line
			(start 0.12065 -0.3048)
			(end 0.67945 -0.3048)
			(stroke
				(width 0.1)
				(type default)
			)
			(layer "F.Fab")
		)
		(fp_line
			(start 0.120396 0.3048)
			(end 0.120396 0.2794)
			(stroke
				(width 0.1)
				(type default)
			)
			(layer "F.Fab")
		)
		(fp_line
			(start 0.120396 0.2794)
			(end -0.12065 0.2794)
			(stroke
				(width 0.1)
				(type default)
			)
			(layer "F.Fab")
		)
		(fp_line
			(start -0.12065 0.3048)
			(end -0.67945 0.3048)
			(stroke
				(width 0.1)
				(type default)
			)
			(layer "F.Fab")
		)
		(fp_line
			(start -0.12065 0.2794)
			(end -0.12065 0.3048)
			(stroke
				(width 0.1)
				(type default)
			)
			(layer "F.Fab")
		)
		(fp_line
			(start -0.12065 -0.2794)
			(end 0.12065 -0.2794)
			(stroke
				(width 0.1)
				(type default)
			)
			(layer "F.Fab")
		)
		(fp_line
			(start -0.12065 -0.305054)
			(end -0.12065 -0.2794)
			(stroke
				(width 0.1)
				(type default)
			)
			(layer "F.Fab")
		)
		(fp_line
			(start -0.67945 0.3048)
			(end -0.67945 -0.305054)
			(stroke
				(width 0.1)
				(type default)
			)
			(layer "F.Fab")
		)
		(fp_line
			(start -0.67945 -0.305054)
			(end -0.12065 -0.305054)
			(stroke
				(width 0.1)
				(type default)
			)
			(layer "F.Fab")
		)
		(pad "1" smd circle
			(at -0.40005 0 180)
			(size 0 0)
			(layers "F.Cu" "F.Mask" "F.Paste")
			(net "P2V5_AUX")
		)
		(pad "2" smd circle
			(at 0.40005 0 180)
			(size 0 0)
			(layers "F.Cu" "F.Mask" "F.Paste")
			(net "U39_ADJ")
		)
	)
	(footprint ""
		(layer "F.Cu")
		(at 6.096 -55.372 180)
		(property "Reference" "PC206"
			(at 0 0 180)
			(layer "F.SilkS")
			(hide yes)
			(effects
				(font
					(size 1.27 1.27)
				)
			)
		)
		(property "Value" ""
			(at 0 0 180)
			(layer "F.Fab")
			(effects
				(font
					(size 1.27 1.27)
				)
			)
		)
		(duplicate_pad_numbers_are_jumpers no)
		(fp_line
			(start 1.524 0.762)
			(end -1.524 0.762)
			(stroke
				(width 0.1524)
				(type default)
			)
			(layer "F.SilkS")
		)
		(fp_line
			(start 1.524 -0.762)
			(end 1.524 0.762)
			(stroke
				(width 0.1524)
				(type default)
			)
			(layer "F.SilkS")
		)
		(fp_line
			(start -1.524 0.762)
			(end -1.524 -0.762)
			(stroke
				(width 0.1524)
				(type default)
			)
			(layer "F.SilkS")
		)
		(fp_line
			(start -1.524 -0.762)
			(end 1.524 -0.762)
			(stroke
				(width 0.1524)
				(type default)
			)
			(layer "F.SilkS")
		)
		(fp_line
			(start 1.1049 0.724916)
			(end 1.1049 -0.724916)
			(stroke
				(width 0.1)
				(type default)
			)
			(layer "F.Fab")
		)
		(fp_line
			(start 1.1049 -0.724916)
			(end -1.1049 -0.724916)
			(stroke
				(width 0.1)
				(type default)
			)
			(layer "F.Fab")
		)
		(fp_line
			(start -1.1049 0.724916)
			(end 1.1049 0.724916)
			(stroke
				(width 0.1)
				(type default)
			)
			(layer "F.Fab")
		)
		(fp_line
			(start -1.1049 -0.724916)
			(end -1.1049 0.724916)
			(stroke
				(width 0.1)
				(type default)
			)
			(layer "F.Fab")
		)
		(pad "1" smd rect
			(at -0.889 0)
			(size 1.016 1.27)
			(layers "F.Cu" "F.Mask" "F.Paste")
			(net "SW_P5V_AUX_FLT")
		)
		(pad "2" smd rect
			(at 0.889 0)
			(size 1.016 1.27)
			(layers "F.Cu" "F.Mask" "F.Paste")
			(net "GND")
		)
	)
	(footprint ""
		(layer "F.Cu")
		(at 9.779 -9.652 180)
		(property "Reference" "C198"
			(at 0 0 180)
			(layer "F.SilkS")
			(hide yes)
			(effects
				(font
					(size 1.27 1.27)
				)
			)
		)
		(property "Value" ""
			(at 0 0 180)
			(layer "F.Fab")
			(effects
				(font
					(size 1.27 1.27)
				)
			)
		)
		(duplicate_pad_numbers_are_jumpers no)
		(fp_line
			(start 0.7874 0.4064)
			(end -0.7874 0.4064)
			(stroke
				(width 0.1524)
				(type default)
			)
			(layer "F.SilkS")
		)
		(fp_line
			(start 0.7874 -0.4064)
			(end 0.7874 0.4064)
			(stroke
				(width 0.1524)
				(type default)
			)
			(layer "F.SilkS")
		)
		(fp_line
			(start -0.7874 0.4064)
			(end -0.7874 -0.4064)
			(stroke
				(width 0.1524)
				(type default)
			)
			(layer "F.SilkS")
		)
		(fp_line
			(start -0.7874 -0.4064)
			(end 0.7874 -0.4064)
			(stroke
				(width 0.1524)
				(type default)
			)
			(layer "F.SilkS")
		)
		(fp_line
			(start 0.67945 0.3048)
			(end 0.120396 0.3048)
			(stroke
				(width 0.1)
				(type default)
			)
			(layer "F.Fab")
		)
		(fp_line
			(start 0.67945 -0.3048)
			(end 0.67945 0.3048)
			(stroke
				(width 0.1)
				(type default)
			)
			(layer "F.Fab")
		)
		(fp_line
			(start 0.12065 -0.2794)
			(end 0.12065 -0.3048)
			(stroke
				(width 0.1)
				(type default)
			)
			(layer "F.Fab")
		)
		(fp_line
			(start 0.12065 -0.3048)
			(end 0.67945 -0.3048)
			(stroke
				(width 0.1)
				(type default)
			)
			(layer "F.Fab")
		)
		(fp_line
			(start 0.120396 0.3048)
			(end 0.120396 0.2794)
			(stroke
				(width 0.1)
				(type default)
			)
			(layer "F.Fab")
		)
		(fp_line
			(start 0.120396 0.2794)
			(end -0.12065 0.2794)
			(stroke
				(width 0.1)
				(type default)
			)
			(layer "F.Fab")
		)
		(fp_line
			(start -0.12065 0.3048)
			(end -0.67945 0.3048)
			(stroke
				(width 0.1)
				(type default)
			)
			(layer "F.Fab")
		)
		(fp_line
			(start -0.12065 0.2794)
			(end -0.12065 0.3048)
			(stroke
				(width 0.1)
				(type default)
			)
			(layer "F.Fab")
		)
		(fp_line
			(start -0.12065 -0.2794)
			(end 0.12065 -0.2794)
			(stroke
				(width 0.1)
				(type default)
			)
			(layer "F.Fab")
		)
		(fp_line
			(start -0.12065 -0.305054)
			(end -0.12065 -0.2794)
			(stroke
				(width 0.1)
				(type default)
			)
			(layer "F.Fab")
		)
		(fp_line
			(start -0.67945 0.3048)
			(end -0.67945 -0.305054)
			(stroke
				(width 0.1)
				(type default)
			)
			(layer "F.Fab")
		)
		(fp_line
			(start -0.67945 -0.305054)
			(end -0.12065 -0.305054)
			(stroke
				(width 0.1)
				(type default)
			)
			(layer "F.Fab")
		)
		(pad "1" smd circle
			(at -0.40005 0 180)
			(size 0 0)
			(layers "F.Cu" "F.Mask" "F.Paste")
			(net "REAR_PWR_BTN_N")
		)
		(pad "2" smd circle
			(at 0.40005 0 180)
			(size 0 0)
			(layers "F.Cu" "F.Mask" "F.Paste")
			(net "GND")
		)
	)
	(footprint ""
		(layer "F.Cu")
		(at 51.816 -69.342)
		(property "Reference" "R699"
			(at 0 0 0)
			(layer "F.SilkS")
			(hide yes)
			(effects
				(font
					(size 1.27 1.27)
				)
			)
		)
		(property "Value" ""
			(at 0 0 0)
			(layer "F.Fab")
			(effects
				(font
					(size 1.27 1.27)
				)
			)
		)
		(duplicate_pad_numbers_are_jumpers no)
		(fp_line
			(start -0.7874 -0.4064)
			(end 0.7874 -0.4064)
			(stroke
				(width 0.1524)
				(type default)
			)
			(layer "F.SilkS")
		)
		(fp_line
			(start -0.7874 0.4064)
			(end -0.7874 -0.4064)
			(stroke
				(width 0.1524)
				(type default)
			)
			(layer "F.SilkS")
		)
		(fp_line
			(start 0.7874 -0.4064)
			(end 0.7874 0.4064)
			(stroke
				(width 0.1524)
				(type default)
			)
			(layer "F.SilkS")
		)
		(fp_line
			(start 0.7874 0.4064)
			(end -0.7874 0.4064)
			(stroke
				(width 0.1524)
				(type default)
			)
			(layer "F.SilkS")
		)
		(fp_line
			(start -0.67945 -0.305054)
			(end -0.12065 -0.305054)
			(stroke
				(width 0.1)
				(type default)
			)
			(layer "F.Fab")
		)
		(fp_line
			(start -0.67945 0.3048)
			(end -0.67945 -0.305054)
			(stroke
				(width 0.1)
				(type default)
			)
			(layer "F.Fab")
		)
		(fp_line
			(start -0.12065 -0.305054)
			(end -0.12065 -0.2794)
			(stroke
				(width 0.1)
				(type default)
			)
			(layer "F.Fab")
		)
		(fp_line
			(start -0.12065 -0.2794)
			(end 0.12065 -0.2794)
			(stroke
				(width 0.1)
				(type default)
			)
			(layer "F.Fab")
		)
		(fp_line
			(start -0.12065 0.2794)
			(end -0.12065 0.3048)
			(stroke
				(width 0.1)
				(type default)
			)
			(layer "F.Fab")
		)
		(fp_line
			(start -0.12065 0.3048)
			(end -0.67945 0.3048)
			(stroke
				(width 0.1)
				(type default)
			)
			(layer "F.Fab")
		)
		(fp_line
			(start 0.120396 0.2794)
			(end -0.12065 0.2794)
			(stroke
				(width 0.1)
				(type default)
			)
			(layer "F.Fab")
		)
		(fp_line
			(start 0.120396 0.3048)
			(end 0.120396 0.2794)
			(stroke
				(width 0.1)
				(type default)
			)
			(layer "F.Fab")
		)
		(fp_line
			(start 0.12065 -0.3048)
			(end 0.67945 -0.3048)
			(stroke
				(width 0.1)
				(type default)
			)
			(layer "F.Fab")
		)
		(fp_line
			(start 0.12065 -0.2794)
			(end 0.12065 -0.3048)
			(stroke
				(width 0.1)
				(type default)
			)
			(layer "F.Fab")
		)
		(fp_line
			(start 0.67945 -0.3048)
			(end 0.67945 0.3048)
			(stroke
				(width 0.1)
				(type default)
			)
			(layer "F.Fab")
		)
		(fp_line
			(start 0.67945 0.3048)
			(end 0.120396 0.3048)
			(stroke
				(width 0.1)
				(type default)
			)
			(layer "F.Fab")
		)
		(pad "1" smd circle
			(at -0.40005 0)
			(size 0 0)
			(layers "F.Cu" "F.Mask" "F.Paste")
			(net "P3V3_AUX")
		)
		(pad "2" smd circle
			(at 0.40005 0)
			(size 0 0)
			(layers "F.Cu" "F.Mask" "F.Paste")
			(net "SPI_BMC_BOOT_CLK")
		)
	)
)
